# S9S_MB_2U (Grand Teton) — schematic netlist excerpt (pin names and nets, part order shuffled) for the footprints in the layout excerpt that follows; sources: Cadence DE-HDL packaged netlist, KiCad conversion of 03242023_DA0F0TMBIJ0_F0T_Motherboard_J_brd_V01_OCP.brd

R1009  Q_RES  1K 1% EMPTY  pkg 0402LF  page 119 : A = PVNN_TERM_CPU0 ; B = PU_TAP_ODT_CPU0_EN

Q15  MOSFET_NCH_DUAL  PJT138K IC  pkg SOT363XD  page 235
  S1  = GND
  G1  = FM_SMB_PEHPCPU0_PCIE_ALERT_R_N
  D2  = FM_PEHPCPU0_ALERT_N
  S2  = GND
  G2  = FM_SMB_CPU0_ALERT_R1
  D1  = FM_SMB_CPU0_ALERT_R1

(kicad_pcb
	(version 20260206)
	(generator "pcbnew")
	(generator_version "10.0")
	(general
		(thickness 1.6)
		(legacy_teardrops no)
	)
	(paper "A4")
	(title_block
		(title "03242023_DA0F0TMBIJ0_F0T_Motherboard_J_brd_V01_OCP.brd")
		(comment 1 "Grand Teton / footprints 6055-6056 of 6105")
	)
	(layers
		(0 "F.Cu" signal "TOP")
		(4 "In1.Cu" signal "GND")
		(6 "In2.Cu" signal "IN1")
		(8 "In3.Cu" signal "GND1")
		(10 "In4.Cu" signal "IN2")
		(12 "In5.Cu" signal "GND2")
		(14 "In6.Cu" signal "IN3")
		(16 "In7.Cu" signal "GND3")
		(18 "In8.Cu" signal "VCC")
		(20 "In9.Cu" signal "VCC1")
		(22 "In10.Cu" signal "GND4")
		(24 "In11.Cu" signal "IN4")
		(26 "In12.Cu" signal "GND5")
		(28 "In13.Cu" signal "IN5")
		(30 "In14.Cu" signal "GND6")
		(32 "In15.Cu" signal "IN6")
		(34 "In16.Cu" signal "GND7")
		(2 "B.Cu" signal "BOTTOM")
		(9 "F.Adhes" user "F.Adhesive")
		(11 "B.Adhes" user "B.Adhesive")
		(13 "F.Paste" user "Package Geometry/Pastemask Top")
		(15 "B.Paste" user "Package Geometry/Pastemask Bottom")
		(5 "F.SilkS" user "Ref Des/Silkscreen Top")
		(7 "B.SilkS" user "Ref Des/Silkscreen Bottom")
		(1 "F.Mask" user "Board Geometry/Soldermask Top")
		(3 "B.Mask" user "Board Geometry/Soldermask Bottom")
		(17 "Dwgs.User" user "User.Drawings")
		(19 "Cmts.User" user "User.Comments")
		(21 "Eco1.User" user "User.Eco1")
		(23 "Eco2.User" user "User.Eco2")
		(25 "Edge.Cuts" user "Board Geometry/Outline")
		(27 "Margin" user)
		(31 "F.CrtYd" user "Package Geometry/Place Bound Top")
		(29 "B.CrtYd" user "Package Geometry/Place Bound Bottom")
		(35 "F.Fab" user "Ref Des/Assembly Top")
		(33 "B.Fab" user "Ref Des/Assembly Bottom")
	)
	(footprint ""
		(layer "B.Cu")
		(at 365.037624 -183.101488 90)
		(property "Reference" "Q15"
			(at 2.23901 -2.577084 0)
			(unlocked yes)
			(layer "B.SilkS")
			(effects
				(font
					(size 0.7874 0.5842)
					(thickness 0.1524)
				)
				(justify left mirror)
			)
		)
		(property "Value" ""
			(at 0 0 90)
			(layer "B.Fab")
			(effects
				(font
					(size 1.27 1.27)
				)
				(justify mirror)
			)
		)
		(duplicate_pad_numbers_are_jumpers no)
		(fp_line
			(start 1.332738 -1.100074)
			(end 0.4826 -1.100074)
			(stroke
				(width 0.1524)
				(type default)
			)
			(layer "B.SilkS")
		)
		(fp_line
			(start 0.4826 -1.100074)
			(end 0 -0.541274)
			(stroke
				(width 0.1524)
				(type default)
			)
			(layer "B.SilkS")
		)
		(fp_line
			(start -0.4826 -1.100074)
			(end -1.332738 -1.100074)
			(stroke
				(width 0.1524)
				(type default)
			)
			(layer "B.SilkS")
		)
		(fp_line
			(start -1.332738 -1.100074)
			(end -1.332738 1.100074)
			(stroke
				(width 0.1524)
				(type default)
			)
			(layer "B.SilkS")
		)
		(fp_line
			(start 0 -0.541274)
			(end -0.4826 -1.100074)
			(stroke
				(width 0.1524)
				(type default)
			)
			(layer "B.SilkS")
		)
		(fp_line
			(start 1.332738 1.100074)
			(end 1.332738 -1.100074)
			(stroke
				(width 0.1524)
				(type default)
			)
			(layer "B.SilkS")
		)
		(fp_line
			(start -1.332738 1.100074)
			(end 1.332738 1.100074)
			(stroke
				(width 0.1524)
				(type default)
			)
			(layer "B.SilkS")
		)
		(fp_poly
			(pts
				(xy 2.2352 -0.298958) (xy 1.533144 -0.649986) (xy 2.2352 -1.001014)
			)
			(stroke
				(width 0)
				(type default)
			)
			(fill yes)
			(layer "B.SilkS")
		)
		(fp_line
			(start 0.674878 -1.100074)
			(end -0.674878 -1.100074)
			(stroke
				(width 0.1)
				(type default)
			)
			(layer "B.Fab")
		)
		(fp_line
			(start -0.674878 -1.100074)
			(end -0.674878 1.100074)
			(stroke
				(width 0.1)
				(type default)
			)
			(layer "B.Fab")
		)
		(fp_line
			(start 0.674878 1.100074)
			(end 0.674878 -1.100074)
			(stroke
				(width 0.1)
				(type default)
			)
			(layer "B.Fab")
		)
		(fp_line
			(start -0.674878 1.100074)
			(end 0.674878 1.100074)
			(stroke
				(width 0.1)
				(type default)
			)
			(layer "B.Fab")
		)
		(fp_poly
			(pts
				(xy 2.2352 -0.298958) (xy 2.2352 -1.001014) (xy 1.533144 -0.649986)
			)
			(stroke
				(width 0)
				(type default)
			)
			(fill yes)
			(layer "B.Fab")
		)
		(pad "1" smd rect
			(at 0.94996 -0.649986 180)
			(size 0.4318 0.508)
			(layers "B.Cu" "B.Mask" "B.Paste")
			(net "GND")
		)
		(pad "2" smd rect
			(at 0.94996 0 180)
			(size 0.4318 0.508)
			(layers "B.Cu" "B.Mask" "B.Paste")
			(net "FM_SMB_PEHPCPU0_PCIE_ALERT_R_N")
		)
		(pad "3" smd rect
			(at 0.94996 0.649986 180)
			(size 0.4318 0.508)
			(layers "B.Cu" "B.Mask" "B.Paste")
			(net "FM_PEHPCPU0_ALERT_N")
		)
		(pad "4" smd rect
			(at -0.94996 0.649986 180)
			(size 0.4318 0.508)
			(layers "B.Cu" "B.Mask" "B.Paste")
			(net "GND")
		)
		(pad "5" smd rect
			(at -0.94996 0 180)
			(size 0.4318 0.508)
			(layers "B.Cu" "B.Mask" "B.Paste")
			(net "FM_SMB_CPU0_ALERT_R1")
		)
		(pad "6" smd rect
			(at -0.94996 -0.649986 180)
			(size 0.4318 0.508)
			(layers "B.Cu" "B.Mask" "B.Paste")
			(net "FM_SMB_CPU0_ALERT_R1")
		)
	)
	(footprint ""
		(layer "B.Cu")
		(at 318.554862 -191.122046 180)
		(property "Reference" "R1009"
			(at 0 0 0)
			(layer "B.SilkS")
			(hide yes)
			(effects
				(font
					(size 1.27 1.27)
				)
				(justify mirror)
			)
		)
		(property "Value" ""
			(at 0 0 0)
			(layer "B.Fab")
			(effects
				(font
					(size 1.27 1.27)
				)
				(justify mirror)
			)
		)
		(duplicate_pad_numbers_are_jumpers no)
		(fp_line
			(start 0.7874 0.4064)
			(end 0.7874 -0.4064)
			(stroke
				(width 0.1524)
				(type default)
			)
			(layer "B.SilkS")
		)
		(fp_line
			(start 0.7874 -0.4064)
			(end -0.7874 -0.4064)
			(stroke
				(width 0.1524)
				(type default)
			)
			(layer "B.SilkS")
		)
		(fp_line
			(start -0.7874 0.4064)
			(end 0.7874 0.4064)
			(stroke
				(width 0.1524)
				(type default)
			)
			(layer "B.SilkS")
		)
		(fp_line
			(start -0.7874 -0.4064)
			(end -0.7874 0.4064)
			(stroke
				(width 0.1524)
				(type default)
			)
			(layer "B.SilkS")
		)
		(fp_line
			(start 0.67945 0.3048)
			(end 0.67945 -0.305054)
			(stroke
				(width 0.1)
				(type default)
			)
			(layer "B.Fab")
		)
		(fp_line
			(start 0.67945 -0.305054)
			(end 0.12065 -0.305054)
			(stroke
				(width 0.1)
				(type default)
			)
			(layer "B.Fab")
		)
		(fp_line
			(start 0.12065 0.3048)
			(end 0.67945 0.3048)
			(stroke
				(width 0.1)
				(type default)
			)
			(layer "B.Fab")
		)
		(fp_line
			(start 0.12065 0.2794)
			(end 0.12065 0.3048)
			(stroke
				(width 0.1)
				(type default)
			)
			(layer "B.Fab")
		)
		(fp_line
			(start 0.12065 -0.2794)
			(end -0.12065 -0.2794)
			(stroke
				(width 0.1)
				(type default)
			)
			(layer "B.Fab")
		)
		(fp_line
			(start 0.12065 -0.305054)
			(end 0.12065 -0.2794)
			(stroke
				(width 0.1)
				(type default)
			)
			(layer "B.Fab")
		)
		(fp_line
			(start -0.120396 0.3048)
			(end -0.120396 0.2794)
			(stroke
				(width 0.1)
				(type default)
			)
			(layer "B.Fab")
		)
		(fp_line
			(start -0.120396 0.2794)
			(end 0.12065 0.2794)
			(stroke
				(width 0.1)
				(type default)
			)
			(layer "B.Fab")
		)
		(fp_line
			(start -0.12065 -0.2794)
			(end -0.12065 -0.3048)
			(stroke
				(width 0.1)
				(type default)
			)
			(layer "B.Fab")
		)
		(fp_line
			(start -0.12065 -0.3048)
			(end -0.67945 -0.3048)
			(stroke
				(width 0.1)
				(type default)
			)
			(layer "B.Fab")
		)
		(fp_line
			(start -0.67945 0.3048)
			(end -0.120396 0.3048)
			(stroke
				(width 0.1)
				(type default)
			)
			(layer "B.Fab")
		)
		(fp_line
			(start -0.67945 -0.3048)
			(end -0.67945 0.3048)
			(stroke
				(width 0.1)
				(type default)
			)
			(layer "B.Fab")
		)
		(pad "1" smd circle
			(at 0.40005 0)
			(size 0 0)
			(layers "B.Cu" "B.Mask" "B.Paste")
			(net "PVNN_TERM_CPU0")
		)
		(pad "2" smd circle
			(at -0.40005 0)
			(size 0 0)
			(layers "B.Cu" "B.Mask" "B.Paste")
			(net "PU_TAP_ODT_CPU0_EN")
		)
	)
)
